(kicad_pcb
	(version 20260206)
	(generator "pcbnew")
	(generator_version "10.0")
	(general
		(thickness 1.6)
		(legacy_teardrops no)
	)
	(paper "A4")
	(title_block
		(title "04192023_DAF0TMB3IC0_F0TG_MB_C_brd_V02_OCP.brd")
		(comment 1 "Grand Teton / footprints 410-416 of 8354")
	)
	(layers
		(0 "F.Cu" signal "TOP")
		(4 "In1.Cu" signal "GND")
		(6 "In2.Cu" signal "IN1")
		(8 "In3.Cu" signal "GND1")
		(10 "In4.Cu" signal "IN2")
		(12 "In5.Cu" signal "GND2")
		(14 "In6.Cu" signal "IN3")
		(16 "In7.Cu" signal "GND3")
		(18 "In8.Cu" signal "VCC")
		(20 "In9.Cu" signal "VCC1")
		(22 "In10.Cu" signal "GND4")
		(24 "In11.Cu" signal "IN4")
		(26 "In12.Cu" signal "GND5")
		(28 "In13.Cu" signal "IN5")
		(30 "In14.Cu" signal "GND6")
		(32 "In15.Cu" signal "IN6")
		(34 "In16.Cu" signal "GND7")
		(2 "B.Cu" signal "BOTTOM")
		(9 "F.Adhes" user "F.Adhesive")
		(11 "B.Adhes" user "B.Adhesive")
		(13 "F.Paste" user "Package Geometry/Pastemask Top")
		(15 "B.Paste" user "Package Geometry/Pastemask Bottom")
		(5 "F.SilkS" user "Ref Des/Silkscreen Top")
		(7 "B.SilkS" user "Ref Des/Silkscreen Bottom")
		(1 "F.Mask" user "Board Geometry/Soldermask Top")
		(3 "B.Mask" user "Board Geometry/Soldermask Bottom")
		(17 "Dwgs.User" user "User.Drawings")
		(19 "Cmts.User" user "User.Comments")
		(21 "Eco1.User" user "User.Eco1")
		(23 "Eco2.User" user "User.Eco2")
		(25 "Edge.Cuts" user "Board Geometry/Outline")
		(27 "Margin" user)
		(31 "F.CrtYd" user "Package Geometry/Place Bound Top")
		(29 "B.CrtYd" user "Package Geometry/Place Bound Bottom")
		(35 "F.Fab" user "Ref Des/Assembly Top")
		(33 "B.Fab" user "Ref Des/Assembly Bottom")
	)
	(footprint ""
		(layer "F.Cu")
		(at 78.826106 -58.382154 -90)
		(property "Reference" "C2020"
			(at 0 0 270)
			(layer "F.SilkS")
			(hide yes)
			(effects
				(font
					(size 1.27 1.27)
				)
			)
		)
		(property "Value" ""
			(at 0 0 270)
			(layer "F.Fab")
			(effects
				(font
					(size 1.27 1.27)
				)
			)
		)
		(duplicate_pad_numbers_are_jumpers no)
		(fp_line
			(start -0.7874 0.4064)
			(end -0.7874 -0.4064)
			(stroke
				(width 0.1524)
				(type default)
			)
			(layer "F.SilkS")
		)
		(fp_line
			(start 0.7874 0.4064)
			(end -0.7874 0.4064)
			(stroke
				(width 0.1524)
				(type default)
			)
			(layer "F.SilkS")
		)
		(fp_line
			(start -0.7874 -0.4064)
			(end 0.7874 -0.4064)
			(stroke
				(width 0.1524)
				(type default)
			)
			(layer "F.SilkS")
		)
		(fp_line
			(start 0.7874 -0.4064)
			(end 0.7874 0.4064)
			(stroke
				(width 0.1524)
				(type default)
			)
			(layer "F.SilkS")
		)
		(fp_line
			(start -0.67945 0.3048)
			(end -0.67945 -0.305054)
			(stroke
				(width 0.1)
				(type default)
			)
			(layer "F.Fab")
		)
		(fp_line
			(start -0.12065 0.3048)
			(end -0.67945 0.3048)
			(stroke
				(width 0.1)
				(type default)
			)
			(layer "F.Fab")
		)
		(fp_line
			(start 0.120396 0.3048)
			(end 0.120396 0.2794)
			(stroke
				(width 0.1)
				(type default)
			)
			(layer "F.Fab")
		)
		(fp_line
			(start 0.67945 0.3048)
			(end 0.120396 0.3048)
			(stroke
				(width 0.1)
				(type default)
			)
			(layer "F.Fab")
		)
		(fp_line
			(start -0.12065 0.2794)
			(end -0.12065 0.3048)
			(stroke
				(width 0.1)
				(type default)
			)
			(layer "F.Fab")
		)
		(fp_line
			(start 0.120396 0.2794)
			(end -0.12065 0.2794)
			(stroke
				(width 0.1)
				(type default)
			)
			(layer "F.Fab")
		)
		(fp_line
			(start -0.12065 -0.2794)
			(end 0.12065 -0.2794)
			(stroke
				(width 0.1)
				(type default)
			)
			(layer "F.Fab")
		)
		(fp_line
			(start 0.12065 -0.2794)
			(end 0.12065 -0.3048)
			(stroke
				(width 0.1)
				(type default)
			)
			(layer "F.Fab")
		)
		(fp_line
			(start 0.12065 -0.3048)
			(end 0.67945 -0.3048)
			(stroke
				(width 0.1)
				(type default)
			)
			(layer "F.Fab")
		)
		(fp_line
			(start 0.67945 -0.3048)
			(end 0.67945 0.3048)
			(stroke
				(width 0.1)
				(type default)
			)
			(layer "F.Fab")
		)
		(fp_line
			(start -0.67945 -0.305054)
			(end -0.12065 -0.305054)
			(stroke
				(width 0.1)
				(type default)
			)
			(layer "F.Fab")
		)
		(fp_line
			(start -0.12065 -0.305054)
			(end -0.12065 -0.2794)
			(stroke
				(width 0.1)
				(type default)
			)
			(layer "F.Fab")
		)
		(pad "1" smd circle
			(at -0.40005 0 270)
			(size 0 0)
			(layers "F.Cu" "F.Mask" "F.Paste")
			(net "VSENSE_P12V_INA230_3_INP")
		)
		(pad "2" smd circle
			(at 0.40005 0 270)
			(size 0 0)
			(layers "F.Cu" "F.Mask" "F.Paste")
			(net "VSENSE_P12V_INA230_3_INN")
		)
	)
	(footprint ""
		(layer "F.Cu")
		(at 363.645958 -258.795012)
		(property "Reference" "C2563"
			(at 0 0 0)
			(layer "F.SilkS")
			(hide yes)
			(effects
				(font
					(size 1.27 1.27)
				)
			)
		)
		(property "Value" ""
			(at 0 0 0)
			(layer "F.Fab")
			(effects
				(font
					(size 1.27 1.27)
				)
			)
		)
		(duplicate_pad_numbers_are_jumpers no)
		(fp_line
			(start -0.7874 -0.4064)
			(end 0.7874 -0.4064)
			(stroke
				(width 0.1524)
				(type default)
			)
			(layer "F.SilkS")
		)
		(fp_line
			(start -0.7874 0.4064)
			(end -0.7874 -0.4064)
			(stroke
				(width 0.1524)
				(type default)
			)
			(layer "F.SilkS")
		)
		(fp_line
			(start 0.7874 -0.4064)
			(end 0.7874 0.4064)
			(stroke
				(width 0.1524)
				(type default)
			)
			(layer "F.SilkS")
		)
		(fp_line
			(start 0.7874 0.4064)
			(end -0.7874 0.4064)
			(stroke
				(width 0.1524)
				(type default)
			)
			(layer "F.SilkS")
		)
		(fp_line
			(start -0.67945 -0.305054)
			(end -0.12065 -0.305054)
			(stroke
				(width 0.1)
				(type default)
			)
			(layer "F.Fab")
		)
		(fp_line
			(start -0.67945 0.3048)
			(end -0.67945 -0.305054)
			(stroke
				(width 0.1)
				(type default)
			)
			(layer "F.Fab")
		)
		(fp_line
			(start -0.12065 -0.305054)
			(end -0.12065 -0.2794)
			(stroke
				(width 0.1)
				(type default)
			)
			(layer "F.Fab")
		)
		(fp_line
			(start -0.12065 -0.2794)
			(end 0.12065 -0.2794)
			(stroke
				(width 0.1)
				(type default)
			)
			(layer "F.Fab")
		)
		(fp_line
			(start -0.12065 0.2794)
			(end -0.12065 0.3048)
			(stroke
				(width 0.1)
				(type default)
			)
			(layer "F.Fab")
		)
		(fp_line
			(start -0.12065 0.3048)
			(end -0.67945 0.3048)
			(stroke
				(width 0.1)
				(type default)
			)
			(layer "F.Fab")
		)
		(fp_line
			(start 0.120396 0.2794)
			(end -0.12065 0.2794)
			(stroke
				(width 0.1)
				(type default)
			)
			(layer "F.Fab")
		)
		(fp_line
			(start 0.120396 0.3048)
			(end 0.120396 0.2794)
			(stroke
				(width 0.1)
				(type default)
			)
			(layer "F.Fab")
		)
		(fp_line
			(start 0.12065 -0.3048)
			(end 0.67945 -0.3048)
			(stroke
				(width 0.1)
				(type default)
			)
			(layer "F.Fab")
		)
		(fp_line
			(start 0.12065 -0.2794)
			(end 0.12065 -0.3048)
			(stroke
				(width 0.1)
				(type default)
			)
			(layer "F.Fab")
		)
		(fp_line
			(start 0.67945 -0.3048)
			(end 0.67945 0.3048)
			(stroke
				(width 0.1)
				(type default)
			)
			(layer "F.Fab")
		)
		(fp_line
			(start 0.67945 0.3048)
			(end 0.120396 0.3048)
			(stroke
				(width 0.1)
				(type default)
			)
			(layer "F.Fab")
		)
		(pad "1" smd circle
			(at -0.40005 0)
			(size 0 0)
			(layers "F.Cu" "F.Mask" "F.Paste")
			(net "PVDDCR_SOC_P0")
		)
		(pad "2" smd circle
			(at 0.40005 0)
			(size 0 0)
			(layers "F.Cu" "F.Mask" "F.Paste")
			(net "GND")
		)
	)
	(footprint ""
		(layer "F.Cu")
		(at 432.308 -405.9174)
		(property "Reference" "R1405"
			(at 0 0 0)
			(layer "F.SilkS")
			(hide yes)
			(effects
				(font
					(size 1.27 1.27)
				)
			)
		)
		(property "Value" ""
			(at 0 0 0)
			(layer "F.Fab")
			(effects
				(font
					(size 1.27 1.27)
				)
			)
		)
		(duplicate_pad_numbers_are_jumpers no)
		(fp_line
			(start -0.32512 -0.175006)
			(end 0.32512 -0.175006)
			(stroke
				(width 0.1)
				(type default)
			)
			(layer "F.Fab")
		)
		(fp_line
			(start -0.32512 0.175006)
			(end -0.32512 -0.175006)
			(stroke
				(width 0.1)
				(type default)
			)
			(layer "F.Fab")
		)
		(fp_line
			(start 0.32512 -0.175006)
			(end 0.32512 0.175006)
			(stroke
				(width 0.1)
				(type default)
			)
			(layer "F.Fab")
		)
		(fp_line
			(start 0.32512 0.175006)
			(end -0.32512 0.175006)
			(stroke
				(width 0.1)
				(type default)
			)
			(layer "F.Fab")
		)
		(pad "1" smd rect
			(at -0.2667 0)
			(size 0.3048 0.381)
			(layers "F.Cu" "F.Mask" "F.Paste")
			(net "P1V8_CPU0_RT_1D")
		)
		(pad "2" smd rect
			(at 0.2667 0 180)
			(size 0.3048 0.381)
			(layers "F.Cu" "F.Mask" "F.Paste")
			(net "RXDET_BYP_RT_CPU0_P2")
		)
	)
	(footprint ""
		(layer "F.Cu")
		(at 461.720946 -103.614728)
		(property "Reference" "C593"
			(at 0 0 0)
			(layer "F.SilkS")
			(hide yes)
			(effects
				(font
					(size 1.27 1.27)
				)
			)
		)
		(property "Value" ""
			(at 0 0 0)
			(layer "F.Fab")
			(effects
				(font
					(size 1.27 1.27)
				)
			)
		)
		(duplicate_pad_numbers_are_jumpers no)
		(fp_line
			(start -0.7874 -0.4064)
			(end 0.7874 -0.4064)
			(stroke
				(width 0.1524)
				(type default)
			)
			(layer "F.SilkS")
		)
		(fp_line
			(start -0.7874 0.4064)
			(end -0.7874 -0.4064)
			(stroke
				(width 0.1524)
				(type default)
			)
			(layer "F.SilkS")
		)
		(fp_line
			(start 0.7874 -0.4064)
			(end 0.7874 0.4064)
			(stroke
				(width 0.1524)
				(type default)
			)
			(layer "F.SilkS")
		)
		(fp_line
			(start 0.7874 0.4064)
			(end -0.7874 0.4064)
			(stroke
				(width 0.1524)
				(type default)
			)
			(layer "F.SilkS")
		)
		(fp_line
			(start -0.67945 -0.305054)
			(end -0.12065 -0.305054)
			(stroke
				(width 0.1)
				(type default)
			)
			(layer "F.Fab")
		)
		(fp_line
			(start -0.67945 0.3048)
			(end -0.67945 -0.305054)
			(stroke
				(width 0.1)
				(type default)
			)
			(layer "F.Fab")
		)
		(fp_line
			(start -0.12065 -0.305054)
			(end -0.12065 -0.2794)
			(stroke
				(width 0.1)
				(type default)
			)
			(layer "F.Fab")
		)
		(fp_line
			(start -0.12065 -0.2794)
			(end 0.12065 -0.2794)
			(stroke
				(width 0.1)
				(type default)
			)
			(layer "F.Fab")
		)
		(fp_line
			(start -0.12065 0.2794)
			(end -0.12065 0.3048)
			(stroke
				(width 0.1)
				(type default)
			)
			(layer "F.Fab")
		)
		(fp_line
			(start -0.12065 0.3048)
			(end -0.67945 0.3048)
			(stroke
				(width 0.1)
				(type default)
			)
			(layer "F.Fab")
		)
		(fp_line
			(start 0.120396 0.2794)
			(end -0.12065 0.2794)
			(stroke
				(width 0.1)
				(type default)
			)
			(layer "F.Fab")
		)
		(fp_line
			(start 0.120396 0.3048)
			(end 0.120396 0.2794)
			(stroke
				(width 0.1)
				(type default)
			)
			(layer "F.Fab")
		)
		(fp_line
			(start 0.12065 -0.3048)
			(end 0.67945 -0.3048)
			(stroke
				(width 0.1)
				(type default)
			)
			(layer "F.Fab")
		)
		(fp_line
			(start 0.12065 -0.2794)
			(end 0.12065 -0.3048)
			(stroke
				(width 0.1)
				(type default)
			)
			(layer "F.Fab")
		)
		(fp_line
			(start 0.67945 -0.3048)
			(end 0.67945 0.3048)
			(stroke
				(width 0.1)
				(type default)
			)
			(layer "F.Fab")
		)
		(fp_line
			(start 0.67945 0.3048)
			(end 0.120396 0.3048)
			(stroke
				(width 0.1)
				(type default)
			)
			(layer "F.Fab")
		)
		(pad "1" smd circle
			(at -0.40005 0)
			(size 0 0)
			(layers "F.Cu" "F.Mask" "F.Paste")
			(net "P3V3_AUX")
		)
		(pad "2" smd circle
			(at 0.40005 0)
			(size 0 0)
			(layers "F.Cu" "F.Mask" "F.Paste")
			(net "GND")
		)
	)
	(footprint ""
		(layer "F.Cu")
		(at 282.133294 -437.2737)
		(property "Reference" "Q145"
			(at -1.4224 -1.768348 0)
			(unlocked yes)
			(layer "F.SilkS")
			(effects
				(font
					(size 0.7874 0.5842)
					(thickness 0.1524)
				)
				(justify left)
			)
		)
		(property "Value" ""
			(at 0 0 0)
			(layer "F.Fab")
			(effects
				(font
					(size 1.27 1.27)
				)
			)
		)
		(duplicate_pad_numbers_are_jumpers no)
		(fp_line
			(start -1.332738 -1.100074)
			(end -0.4826 -1.100074)
			(stroke
				(width 0.1524)
				(type default)
			)
			(layer "F.SilkS")
		)
		(fp_line
			(start -1.332738 1.100074)
			(end -1.332738 -1.100074)
			(stroke
				(width 0.1524)
				(type default)
			)
			(layer "F.SilkS")
		)
		(fp_line
			(start -0.4826 -1.100074)
			(end 0 -0.541274)
			(stroke
				(width 0.1524)
				(type default)
			)
			(layer "F.SilkS")
		)
		(fp_line
			(start 0 -0.541274)
			(end 0.4826 -1.100074)
			(stroke
				(width 0.1524)
				(type default)
			)
			(layer "F.SilkS")
		)
		(fp_line
			(start 0.4826 -1.100074)
			(end 1.332738 -1.100074)
			(stroke
				(width 0.1524)
				(type default)
			)
			(layer "F.SilkS")
		)
		(fp_line
			(start 1.332738 -1.100074)
			(end 1.332738 1.100074)
			(stroke
				(width 0.1524)
				(type default)
			)
			(layer "F.SilkS")
		)
		(fp_line
			(start 1.332738 1.100074)
			(end -1.332738 1.100074)
			(stroke
				(width 0.1524)
				(type default)
			)
			(layer "F.SilkS")
		)
		(fp_poly
			(pts
				(xy -2.252726 -1.230376) (xy -1.756156 -1.726946) (xy -1.507998 -0.982218)
			)
			(stroke
				(width 0)
				(type default)
			)
			(fill yes)
			(layer "F.SilkS")
		)
		(fp_line
			(start -0.674878 -1.100074)
			(end 0.674878 -1.100074)
			(stroke
				(width 0.1)
				(type default)
			)
			(layer "F.Fab")
		)
		(fp_line
			(start -0.674878 1.100074)
			(end -0.674878 -1.100074)
			(stroke
				(width 0.1)
				(type default)
			)
			(layer "F.Fab")
		)
		(fp_line
			(start 0.674878 -1.100074)
			(end 0.674878 1.100074)
			(stroke
				(width 0.1)
				(type default)
			)
			(layer "F.Fab")
		)
		(fp_line
			(start 0.674878 1.100074)
			(end -0.674878 1.100074)
			(stroke
				(width 0.1)
				(type default)
			)
			(layer "F.Fab")
		)
		(fp_poly
			(pts
				(xy -2.2352 -0.298958) (xy -2.2352 -1.001014) (xy -1.533144 -0.649986)
			)
			(stroke
				(width 0)
				(type default)
			)
			(fill yes)
			(layer "F.Fab")
		)
		(pad "1" smd rect
			(at -0.94996 -0.649986 90)
			(size 0.4318 0.508)
			(layers "F.Cu" "F.Mask" "F.Paste")
			(net "GND")
		)
		(pad "2" smd rect
			(at -0.94996 0 90)
			(size 0.4318 0.508)
			(layers "F.Cu" "F.Mask" "F.Paste")
			(net "HPDB_HSC_PWRGD")
		)
		(pad "3" smd rect
			(at -0.94996 0.649986 90)
			(size 0.4318 0.508)
			(layers "F.Cu" "F.Mask" "F.Paste")
			(net "HPDB_HSC_PWRGD_ISO")
		)
		(pad "4" smd rect
			(at 0.94996 0.649986 90)
			(size 0.4318 0.508)
			(layers "F.Cu" "F.Mask" "F.Paste")
			(net "GND")
		)
		(pad "5" smd rect
			(at 0.94996 0 90)
			(size 0.4318 0.508)
			(layers "F.Cu" "F.Mask" "F.Paste")
			(net "HPDB_HSC_PWRGD_N")
		)
		(pad "6" smd rect
			(at 0.94996 -0.649986 90)
			(size 0.4318 0.508)
			(layers "F.Cu" "F.Mask" "F.Paste")
			(net "HPDB_HSC_PWRGD_N")
		)
	)
	(footprint ""
		(layer "F.Cu")
		(at 398.893538 -393.96416)
		(property "Reference" "R1070"
			(at 0 0 0)
			(layer "F.SilkS")
			(hide yes)
			(effects
				(font
					(size 1.27 1.27)
				)
			)
		)
		(property "Value" ""
			(at 0 0 0)
			(layer "F.Fab")
			(effects
				(font
					(size 1.27 1.27)
				)
			)
		)
		(duplicate_pad_numbers_are_jumpers no)
		(fp_line
			(start -0.32512 -0.175006)
			(end 0.32512 -0.175006)
			(stroke
				(width 0.1)
				(type default)
			)
			(layer "F.Fab")
		)
		(fp_line
			(start -0.32512 0.175006)
			(end -0.32512 -0.175006)
			(stroke
				(width 0.1)
				(type default)
			)
			(layer "F.Fab")
		)
		(fp_line
			(start 0.32512 -0.175006)
			(end 0.32512 0.175006)
			(stroke
				(width 0.1)
				(type default)
			)
			(layer "F.Fab")
		)
		(fp_line
			(start 0.32512 0.175006)
			(end -0.32512 0.175006)
			(stroke
				(width 0.1)
				(type default)
			)
			(layer "F.Fab")
		)
		(pad "1" smd rect
			(at -0.2667 0)
			(size 0.3048 0.381)
			(layers "F.Cu" "F.Mask" "F.Paste")
			(net "GPIO2_RT_CPU0_P2")
		)
		(pad "2" smd rect
			(at 0.2667 0 180)
			(size 0.3048 0.381)
			(layers "F.Cu" "F.Mask" "F.Paste")
			(net "GND")
		)
	)
	(footprint ""
		(layer "F.Cu")
		(at 364.314486 -408.931364)
		(property "Reference" "R9017"
			(at 0 0 0)
			(layer "F.SilkS")
			(hide yes)
			(effects
				(font
					(size 1.27 1.27)
				)
			)
		)
		(property "Value" ""
			(at 0 0 0)
			(layer "F.Fab")
			(effects
				(font
					(size 1.27 1.27)
				)
			)
		)
		(duplicate_pad_numbers_are_jumpers no)
		(fp_line
			(start -0.7874 -0.4064)
			(end 0.7874 -0.4064)
			(stroke
				(width 0.1524)
				(type default)
			)
			(layer "F.SilkS")
		)
		(fp_line
			(start -0.7874 0.4064)
			(end -0.7874 -0.4064)
			(stroke
				(width 0.1524)
				(type default)
			)
			(layer "F.SilkS")
		)
		(fp_line
			(start 0.7874 -0.4064)
			(end 0.7874 0.4064)
			(stroke
				(width 0.1524)
				(type default)
			)
			(layer "F.SilkS")
		)
		(fp_line
			(start 0.7874 0.4064)
			(end -0.7874 0.4064)
			(stroke
				(width 0.1524)
				(type default)
			)
			(layer "F.SilkS")
		)
		(fp_line
			(start -0.67945 -0.305054)
			(end -0.12065 -0.305054)
			(stroke
				(width 0.1)
				(type default)
			)
			(layer "F.Fab")
		)
		(fp_line
			(start -0.67945 0.3048)
			(end -0.67945 -0.305054)
			(stroke
				(width 0.1)
				(type default)
			)
			(layer "F.Fab")
		)
		(fp_line
			(start -0.12065 -0.305054)
			(end -0.12065 -0.2794)
			(stroke
				(width 0.1)
				(type default)
			)
			(layer "F.Fab")
		)
		(fp_line
			(start -0.12065 -0.2794)
			(end 0.12065 -0.2794)
			(stroke
				(width 0.1)
				(type default)
			)
			(layer "F.Fab")
		)
		(fp_line
			(start -0.12065 0.2794)
			(end -0.12065 0.3048)
			(stroke
				(width 0.1)
				(type default)
			)
			(layer "F.Fab")
		)
		(fp_line
			(start -0.12065 0.3048)
			(end -0.67945 0.3048)
			(stroke
				(width 0.1)
				(type default)
			)
			(layer "F.Fab")
		)
		(fp_line
			(start 0.120396 0.2794)
			(end -0.12065 0.2794)
			(stroke
				(width 0.1)
				(type default)
			)
			(layer "F.Fab")
		)
		(fp_line
			(start 0.120396 0.3048)
			(end 0.120396 0.2794)
			(stroke
				(width 0.1)
				(type default)
			)
			(layer "F.Fab")
		)
		(fp_line
			(start 0.12065 -0.3048)
			(end 0.67945 -0.3048)
			(stroke
				(width 0.1)
				(type default)
			)
			(layer "F.Fab")
		)
		(fp_line
			(start 0.12065 -0.2794)
			(end 0.12065 -0.3048)
			(stroke
				(width 0.1)
				(type default)
			)
			(layer "F.Fab")
		)
		(fp_line
			(start 0.67945 -0.3048)
			(end 0.67945 0.3048)
			(stroke
				(width 0.1)
				(type default)
			)
			(layer "F.Fab")
		)
		(fp_line
			(start 0.67945 0.3048)
			(end 0.120396 0.3048)
			(stroke
				(width 0.1)
				(type default)
			)
			(layer "F.Fab")
		)
		(pad "1" smd circle
			(at -0.40005 0)
			(size 0 0)
			(layers "F.Cu" "F.Mask" "F.Paste")
			(net "P3V3_AUX")
		)
		(pad "2" smd circle
			(at 0.40005 0)
			(size 0 0)
			(layers "F.Cu" "F.Mask" "F.Paste")
			(net "PRSNT_CABLE_GPU_A3_ISO_N")
		)
	)
)
